# S9S_MB_2U (Grand Teton) — schematic netlist excerpt (pin names and nets, part order shuffled) for the footprints in the layout excerpt that follows; sources: Cadence DE-HDL packaged netlist, KiCad conversion of 03242023_DA0F0TMBIJ0_F0T_Motherboard_J_brd_V01_OCP.brd

C359  Q_CAP  47UF 4V 20% X6S  pkg C0805  page 75 : A = PVCCIN_CPU0 ; B = GND
PR153  Q_RES  2.2 1% CHIP  pkg 0402LF  page 267 : A = PVCCIN_CPU0_PVCC ; B = PVCCIN_CPU0_VDD1
R110  Q_RES  33.2 1% CHIP  pkg 0402LF  page 223 : A = FM_PLD_CLKS_DEV_R_EN ; B = FM_PLD_CLKS_DEV_EN

(kicad_pcb
	(version 20260206)
	(generator "pcbnew")
	(generator_version "10.0")
	(general
		(thickness 1.6)
		(legacy_teardrops no)
	)
	(paper "A4")
	(title_block
		(title "03242023_DA0F0TMBIJ0_F0T_Motherboard_J_brd_V01_OCP.brd")
		(comment 1 "Grand Teton / footprints 4690-4692 of 6105")
	)
	(layers
		(0 "F.Cu" signal "TOP")
		(4 "In1.Cu" signal "GND")
		(6 "In2.Cu" signal "IN1")
		(8 "In3.Cu" signal "GND1")
		(10 "In4.Cu" signal "IN2")
		(12 "In5.Cu" signal "GND2")
		(14 "In6.Cu" signal "IN3")
		(16 "In7.Cu" signal "GND3")
		(18 "In8.Cu" signal "VCC")
		(20 "In9.Cu" signal "VCC1")
		(22 "In10.Cu" signal "GND4")
		(24 "In11.Cu" signal "IN4")
		(26 "In12.Cu" signal "GND5")
		(28 "In13.Cu" signal "IN5")
		(30 "In14.Cu" signal "GND6")
		(32 "In15.Cu" signal "IN6")
		(34 "In16.Cu" signal "GND7")
		(2 "B.Cu" signal "BOTTOM")
		(9 "F.Adhes" user "F.Adhesive")
		(11 "B.Adhes" user "B.Adhesive")
		(13 "F.Paste" user "Package Geometry/Pastemask Top")
		(15 "B.Paste" user "Package Geometry/Pastemask Bottom")
		(5 "F.SilkS" user "Ref Des/Silkscreen Top")
		(7 "B.SilkS" user "Ref Des/Silkscreen Bottom")
		(1 "F.Mask" user "Board Geometry/Soldermask Top")
		(3 "B.Mask" user "Board Geometry/Soldermask Bottom")
		(17 "Dwgs.User" user "User.Drawings")
		(19 "Cmts.User" user "User.Comments")
		(21 "Eco1.User" user "User.Eco1")
		(23 "Eco2.User" user "User.Eco2")
		(25 "Edge.Cuts" user "Board Geometry/Outline")
		(27 "Margin" user)
		(31 "F.CrtYd" user "Package Geometry/Place Bound Top")
		(29 "B.CrtYd" user "Package Geometry/Place Bound Bottom")
		(35 "F.Fab" user "Ref Des/Assembly Top")
		(33 "B.Fab" user "Ref Des/Assembly Bottom")
	)
	(footprint ""
		(layer "B.Cu")
		(at 342.536526 -334.752442 -90)
		(property "Reference" "PR153"
			(at 0 0 90)
			(layer "B.SilkS")
			(hide yes)
			(effects
				(font
					(size 1.27 1.27)
				)
				(justify mirror)
			)
		)
		(property "Value" ""
			(at 0 0 90)
			(layer "B.Fab")
			(effects
				(font
					(size 1.27 1.27)
				)
				(justify mirror)
			)
		)
		(duplicate_pad_numbers_are_jumpers no)
		(fp_line
			(start -0.7874 0.4064)
			(end 0.7874 0.4064)
			(stroke
				(width 0.1524)
				(type default)
			)
			(layer "B.SilkS")
		)
		(fp_line
			(start 0.7874 0.4064)
			(end 0.7874 -0.4064)
			(stroke
				(width 0.1524)
				(type default)
			)
			(layer "B.SilkS")
		)
		(fp_line
			(start -0.7874 -0.4064)
			(end -0.7874 0.4064)
			(stroke
				(width 0.1524)
				(type default)
			)
			(layer "B.SilkS")
		)
		(fp_line
			(start 0.7874 -0.4064)
			(end -0.7874 -0.4064)
			(stroke
				(width 0.1524)
				(type default)
			)
			(layer "B.SilkS")
		)
		(fp_line
			(start -0.67945 0.3048)
			(end -0.120396 0.3048)
			(stroke
				(width 0.1)
				(type default)
			)
			(layer "B.Fab")
		)
		(fp_line
			(start -0.120396 0.3048)
			(end -0.120396 0.2794)
			(stroke
				(width 0.1)
				(type default)
			)
			(layer "B.Fab")
		)
		(fp_line
			(start 0.12065 0.3048)
			(end 0.67945 0.3048)
			(stroke
				(width 0.1)
				(type default)
			)
			(layer "B.Fab")
		)
		(fp_line
			(start 0.67945 0.3048)
			(end 0.67945 -0.305054)
			(stroke
				(width 0.1)
				(type default)
			)
			(layer "B.Fab")
		)
		(fp_line
			(start -0.120396 0.2794)
			(end 0.12065 0.2794)
			(stroke
				(width 0.1)
				(type default)
			)
			(layer "B.Fab")
		)
		(fp_line
			(start 0.12065 0.2794)
			(end 0.12065 0.3048)
			(stroke
				(width 0.1)
				(type default)
			)
			(layer "B.Fab")
		)
		(fp_line
			(start -0.12065 -0.2794)
			(end -0.12065 -0.3048)
			(stroke
				(width 0.1)
				(type default)
			)
			(layer "B.Fab")
		)
		(fp_line
			(start 0.12065 -0.2794)
			(end -0.12065 -0.2794)
			(stroke
				(width 0.1)
				(type default)
			)
			(layer "B.Fab")
		)
		(fp_line
			(start -0.67945 -0.3048)
			(end -0.67945 0.3048)
			(stroke
				(width 0.1)
				(type default)
			)
			(layer "B.Fab")
		)
		(fp_line
			(start -0.12065 -0.3048)
			(end -0.67945 -0.3048)
			(stroke
				(width 0.1)
				(type default)
			)
			(layer "B.Fab")
		)
		(fp_line
			(start 0.12065 -0.305054)
			(end 0.12065 -0.2794)
			(stroke
				(width 0.1)
				(type default)
			)
			(layer "B.Fab")
		)
		(fp_line
			(start 0.67945 -0.305054)
			(end 0.12065 -0.305054)
			(stroke
				(width 0.1)
				(type default)
			)
			(layer "B.Fab")
		)
		(pad "1" smd circle
			(at 0.40005 0 90)
			(size 0 0)
			(layers "B.Cu" "B.Mask" "B.Paste")
			(net "PVCCIN_CPU0_PVCC")
		)
		(pad "2" smd circle
			(at -0.40005 0 90)
			(size 0 0)
			(layers "B.Cu" "B.Mask" "B.Paste")
			(net "PVCCIN_CPU0_VDD1")
		)
	)
	(footprint ""
		(layer "B.Cu")
		(at 353.619308 -255.853946 -90)
		(property "Reference" "C359"
			(at 0 0 90)
			(layer "B.SilkS")
			(hide yes)
			(effects
				(font
					(size 1.27 1.27)
				)
				(justify mirror)
			)
		)
		(property "Value" ""
			(at 0 0 90)
			(layer "B.Fab")
			(effects
				(font
					(size 1.27 1.27)
				)
				(justify mirror)
			)
		)
		(duplicate_pad_numbers_are_jumpers no)
		(fp_line
			(start -1.524 0.762)
			(end 1.524 0.762)
			(stroke
				(width 0.1524)
				(type default)
			)
			(layer "B.SilkS")
		)
		(fp_line
			(start 1.524 0.762)
			(end 1.524 -0.762)
			(stroke
				(width 0.1524)
				(type default)
			)
			(layer "B.SilkS")
		)
		(fp_line
			(start -1.524 -0.762)
			(end -1.524 0.762)
			(stroke
				(width 0.1524)
				(type default)
			)
			(layer "B.SilkS")
		)
		(fp_line
			(start 1.524 -0.762)
			(end -1.524 -0.762)
			(stroke
				(width 0.1524)
				(type default)
			)
			(layer "B.SilkS")
		)
		(fp_line
			(start -1.1049 0.724916)
			(end -1.1049 -0.724916)
			(stroke
				(width 0.1)
				(type default)
			)
			(layer "B.Fab")
		)
		(fp_line
			(start 1.1049 0.724916)
			(end -1.1049 0.724916)
			(stroke
				(width 0.1)
				(type default)
			)
			(layer "B.Fab")
		)
		(fp_line
			(start -1.1049 -0.724916)
			(end 1.1049 -0.724916)
			(stroke
				(width 0.1)
				(type default)
			)
			(layer "B.Fab")
		)
		(fp_line
			(start 1.1049 -0.724916)
			(end 1.1049 0.724916)
			(stroke
				(width 0.1)
				(type default)
			)
			(layer "B.Fab")
		)
		(pad "1" smd rect
			(at 0.889 0 270)
			(size 1.016 1.27)
			(layers "B.Cu" "B.Mask" "B.Paste")
			(net "PVCCIN_CPU0")
		)
		(pad "2" smd rect
			(at -0.889 0 270)
			(size 1.016 1.27)
			(layers "B.Cu" "B.Mask" "B.Paste")
			(net "GND")
		)
	)
	(footprint ""
		(layer "B.Cu")
		(at 233.971846 -132.475224 -90)
		(property "Reference" "R110"
			(at 0 0 90)
			(layer "B.SilkS")
			(hide yes)
			(effects
				(font
					(size 1.27 1.27)
				)
				(justify mirror)
			)
		)
		(property "Value" ""
			(at 0 0 90)
			(layer "B.Fab")
			(effects
				(font
					(size 1.27 1.27)
				)
				(justify mirror)
			)
		)
		(duplicate_pad_numbers_are_jumpers no)
		(fp_line
			(start -0.7874 0.4064)
			(end 0.7874 0.4064)
			(stroke
				(width 0.1524)
				(type default)
			)
			(layer "B.SilkS")
		)
		(fp_line
			(start 0.7874 0.4064)
			(end 0.7874 -0.4064)
			(stroke
				(width 0.1524)
				(type default)
			)
			(layer "B.SilkS")
		)
		(fp_line
			(start -0.7874 -0.4064)
			(end -0.7874 0.4064)
			(stroke
				(width 0.1524)
				(type default)
			)
			(layer "B.SilkS")
		)
		(fp_line
			(start 0.7874 -0.4064)
			(end -0.7874 -0.4064)
			(stroke
				(width 0.1524)
				(type default)
			)
			(layer "B.SilkS")
		)
		(fp_line
			(start -0.67945 0.3048)
			(end -0.120396 0.3048)
			(stroke
				(width 0.1)
				(type default)
			)
			(layer "B.Fab")
		)
		(fp_line
			(start -0.120396 0.3048)
			(end -0.120396 0.2794)
			(stroke
				(width 0.1)
				(type default)
			)
			(layer "B.Fab")
		)
		(fp_line
			(start 0.12065 0.3048)
			(end 0.67945 0.3048)
			(stroke
				(width 0.1)
				(type default)
			)
			(layer "B.Fab")
		)
		(fp_line
			(start 0.67945 0.3048)
			(end 0.67945 -0.305054)
			(stroke
				(width 0.1)
				(type default)
			)
			(layer "B.Fab")
		)
		(fp_line
			(start -0.120396 0.2794)
			(end 0.12065 0.2794)
			(stroke
				(width 0.1)
				(type default)
			)
			(layer "B.Fab")
		)
		(fp_line
			(start 0.12065 0.2794)
			(end 0.12065 0.3048)
			(stroke
				(width 0.1)
				(type default)
			)
			(layer "B.Fab")
		)
		(fp_line
			(start -0.12065 -0.2794)
			(end -0.12065 -0.3048)
			(stroke
				(width 0.1)
				(type default)
			)
			(layer "B.Fab")
		)
		(fp_line
			(start 0.12065 -0.2794)
			(end -0.12065 -0.2794)
			(stroke
				(width 0.1)
				(type default)
			)
			(layer "B.Fab")
		)
		(fp_line
			(start -0.67945 -0.3048)
			(end -0.67945 0.3048)
			(stroke
				(width 0.1)
				(type default)
			)
			(layer "B.Fab")
		)
		(fp_line
			(start -0.12065 -0.3048)
			(end -0.67945 -0.3048)
			(stroke
				(width 0.1)
				(type default)
			)
			(layer "B.Fab")
		)
		(fp_line
			(start 0.12065 -0.305054)
			(end 0.12065 -0.2794)
			(stroke
				(width 0.1)
				(type default)
			)
			(layer "B.Fab")
		)
		(fp_line
			(start 0.67945 -0.305054)
			(end 0.12065 -0.305054)
			(stroke
				(width 0.1)
				(type default)
			)
			(layer "B.Fab")
		)
		(pad "1" smd circle
			(at 0.40005 0 90)
			(size 0 0)
			(layers "B.Cu" "B.Mask" "B.Paste")
			(net "FM_PLD_CLKS_DEV_R_EN")
		)
		(pad "2" smd circle
			(at -0.40005 0 90)
			(size 0 0)
			(layers "B.Cu" "B.Mask" "B.Paste")
			(net "FM_PLD_CLKS_DEV_EN")
		)
	)
)
